(kicad_pcb
	(version 20260206)
	(generator "pcbnew")
	(generator_version "10.0")
	(general
		(thickness 1.6)
		(legacy_teardrops no)
	)
	(paper "A4")
	(title_block
		(title "peb — Lightning_PEB_BRD.brd")
		(comment 1 "Lightning (Wiwynn / Facebook NVMe JBOF) / footprints 862-867 of 2563")
	)
	(layers
		(0 "F.Cu" signal "TOP")
		(4 "In1.Cu" signal "L2GND")
		(6 "In2.Cu" signal "L3")
		(8 "In3.Cu" signal "L4VCC")
		(10 "In4.Cu" signal "L5VCC")
		(12 "In5.Cu" signal "L6")
		(14 "In6.Cu" signal "L7GND")
		(2 "B.Cu" signal "BOTTOM")
		(9 "F.Adhes" user "F.Adhesive")
		(11 "B.Adhes" user "B.Adhesive")
		(13 "F.Paste" user "Package Geometry/Pastemask Top")
		(15 "B.Paste" user "Package Geometry/Pastemask Bottom")
		(5 "F.SilkS" user "Ref Des/Silkscreen Top")
		(7 "B.SilkS" user "Ref Des/Silkscreen Bottom")
		(1 "F.Mask" user "Board Geometry/Soldermask Top")
		(3 "B.Mask" user "Board Geometry/Soldermask Bottom")
		(17 "Dwgs.User" user "User.Drawings")
		(19 "Cmts.User" user "User.Comments")
		(21 "Eco1.User" user "User.Eco1")
		(23 "Eco2.User" user "User.Eco2")
		(25 "Edge.Cuts" user "Board Geometry/Outline")
		(27 "Margin" user)
		(31 "F.CrtYd" user "Package Geometry/Place Bound Top")
		(29 "B.CrtYd" user "Package Geometry/Place Bound Bottom")
		(35 "F.Fab" user "Ref Des/Assembly Top")
		(33 "B.Fab" user "Ref Des/Assembly Bottom")
	)
	(footprint ""
		(layer "F.Cu")
		(at 37.599874 -36.289996)
		(property "Reference" "SKT1"
			(at 0 0 0)
			(layer "F.SilkS")
			(hide yes)
			(effects
				(font
					(size 1.27 1.27)
				)
			)
		)
		(property "Value" "SKT-USB-250-GP"
			(at -10.033 -1.3716 0)
			(unlocked yes)
			(layer "F.Fab")
			(hide yes)
			(effects
				(font
					(size 1.016 1.016)
					(thickness 0.1524)
				)
			)
		)
		(property "Device Type" "67643-3911"
			(at -10.033 -2.8956 0)
			(unlocked yes)
			(layer "F.Fab")
			(hide yes)
			(effects
				(font
					(size 1.016 1.016)
					(thickness 0.1524)
				)
			)
		)
		(duplicate_pad_numbers_are_jumpers no)
		(fp_line
			(start -8.1788 -1.4605)
			(end -7.4549 -1.4605)
			(stroke
				(width 0.1524)
				(type default)
			)
			(layer "F.SilkS")
		)
		(fp_line
			(start -8.1788 1.4605)
			(end -8.1788 -1.4605)
			(stroke
				(width 0.1524)
				(type default)
			)
			(layer "F.SilkS")
		)
		(fp_line
			(start -7.4549 -5.2324)
			(end 7.4549 -5.2324)
			(stroke
				(width 0.1524)
				(type default)
			)
			(layer "F.SilkS")
		)
		(fp_line
			(start -7.4549 -1.4605)
			(end -7.4549 -5.2324)
			(stroke
				(width 0.1524)
				(type default)
			)
			(layer "F.SilkS")
		)
		(fp_line
			(start -7.4549 1.4605)
			(end -8.1788 1.4605)
			(stroke
				(width 0.1524)
				(type default)
			)
			(layer "F.SilkS")
		)
		(fp_line
			(start -7.4549 10.279888)
			(end 7.4549 10.279888)
			(stroke
				(width 0.1524)
				(type default)
			)
			(layer "F.SilkS")
		)
		(fp_line
			(start -7.4549 10.541)
			(end -7.4549 1.4605)
			(stroke
				(width 0.1524)
				(type default)
			)
			(layer "F.SilkS")
		)
		(fp_line
			(start 7.4549 -5.2324)
			(end 7.4549 -1.4605)
			(stroke
				(width 0.1524)
				(type default)
			)
			(layer "F.SilkS")
		)
		(fp_line
			(start 7.4549 -1.4605)
			(end 8.1788 -1.4605)
			(stroke
				(width 0.1524)
				(type default)
			)
			(layer "F.SilkS")
		)
		(fp_line
			(start 7.4549 1.4605)
			(end 7.4549 10.541)
			(stroke
				(width 0.1524)
				(type default)
			)
			(layer "F.SilkS")
		)
		(fp_line
			(start 7.4549 10.541)
			(end -7.4549 10.541)
			(stroke
				(width 0.1524)
				(type default)
			)
			(layer "F.SilkS")
		)
		(fp_line
			(start 8.1788 -1.4605)
			(end 8.1788 1.4605)
			(stroke
				(width 0.1524)
				(type default)
			)
			(layer "F.SilkS")
		)
		(fp_line
			(start 8.1788 1.4605)
			(end 7.4549 1.4605)
			(stroke
				(width 0.1524)
				(type default)
			)
			(layer "F.SilkS")
		)
		(fp_arc
			(start 0 -3.000756)
			(mid 2.041429 -2.709926)
			(end 0 -2.419096)
			(stroke
				(width 0.3048)
				(type default)
			)
			(layer "F.SilkS")
		)
		(fp_arc
			(start 0 -2.419096)
			(mid -2.041429 -2.709926)
			(end 0 -3.000756)
			(stroke
				(width 0.3048)
				(type default)
			)
			(layer "F.SilkS")
		)
		(fp_circle
			(center -6.569964 0)
			(end -4.855464 0)
			(stroke
				(width 0.3048)
				(type default)
			)
			(fill no)
			(layer "F.SilkS")
		)
		(fp_circle
			(center -3.50012 -2.709926)
			(end -2.45872 -2.709926)
			(stroke
				(width 0.3048)
				(type default)
			)
			(fill no)
			(layer "F.SilkS")
		)
		(fp_circle
			(center 3.50012 -2.709926)
			(end 4.54152 -2.709926)
			(stroke
				(width 0.3048)
				(type default)
			)
			(fill no)
			(layer "F.SilkS")
		)
		(fp_circle
			(center 6.569964 0)
			(end 8.284464 0)
			(stroke
				(width 0.3048)
				(type default)
			)
			(fill no)
			(layer "F.SilkS")
		)
		(fp_poly
			(pts
				(xy -7.2009 10.287) (xy -7.2009 0.7493) (xy -7.8486 0.7493) (xy -7.8486 -0.7493) (xy -7.2009 -0.7493)
				(xy -7.2009 -4.9784) (xy 7.2009 -4.9784) (xy 7.2009 -0.7493) (xy 7.8486 -0.7493) (xy 7.8486 0.7493)
				(xy 7.2009 0.7493) (xy 7.2009 10.287)
			)
			(stroke
				(width 0)
				(type default)
			)
			(fill no)
			(layer "F.CrtYd")
		)
		(fp_poly
			(pts
				(xy -7.2009 10.287) (xy -7.2009 0.7493) (xy -7.8486 0.7493) (xy -7.8486 -0.7493) (xy -7.2009 -0.7493)
				(xy -7.2009 -4.9784) (xy 7.2009 -4.9784) (xy 7.2009 -4.4323) (xy 7.7089 -4.4323) (xy 7.7089 -5.4864)
				(xy -7.7089 -5.4864) (xy -7.7089 -1.7145) (xy -8.4328 -1.7145) (xy -8.4328 1.7145) (xy -7.7089 1.7145)
				(xy -7.7089 10.795) (xy 7.7089 10.795) (xy 7.7089 1.7145) (xy 8.4328 1.7145) (xy 8.4328 -1.7145)
				(xy 7.7089 -1.7145) (xy 7.7089 -4.4196) (xy 7.2009 -4.4196) (xy 7.2009 -0.7493) (xy 7.8486 -0.7493)
				(xy 7.8486 0.7493) (xy 7.2009 0.7493) (xy 7.2009 10.287)
			)
			(stroke
				(width 0)
				(type default)
			)
			(fill no)
			(layer "F.CrtYd")
		)
		(fp_poly
			(pts
				(xy -7.7089 10.795) (xy -7.7089 1.7145) (xy -8.4328 1.7145) (xy -8.4328 -1.7145) (xy -7.7089 -1.7145)
				(xy -7.7089 -5.4864) (xy 7.7089 -5.4864) (xy 7.7089 -1.7145) (xy 8.4328 -1.7145) (xy 8.4328 1.7145)
				(xy 7.7089 1.7145) (xy 7.7089 10.795)
			)
			(stroke
				(width 0)
				(type default)
			)
			(fill no)
			(layer "F.Fab")
		)
		(pad "1" thru_hole circle
			(at -3.50012 -2.709926)
			(size 1.3716 1.3716)
			(drill 0.9652)
			(layers "*.Cu" "*.Mask")
			(remove_unused_layers no)
			(net "P5V_USB")
			(clearance 0.1524)
			(thermal_gap 0.1524)
		)
		(pad "2" thru_hole circle
			(at -0.999998 -2.709926)
			(size 1.3716 1.3716)
			(drill 0.9652)
			(layers "*.Cu" "*.Mask")
			(remove_unused_layers no)
			(net "USB_P1_F_DN1")
			(clearance 0.1524)
			(thermal_gap 0.1524)
		)
		(pad "3" thru_hole circle
			(at 0.999998 -2.709926)
			(size 1.3716 1.3716)
			(drill 0.9652)
			(layers "*.Cu" "*.Mask")
			(remove_unused_layers no)
			(net "USB_P1_F_DP1")
			(clearance 0.1524)
			(thermal_gap 0.1524)
		)
		(pad "4" thru_hole circle
			(at 3.50012 -2.709926)
			(size 1.3716 1.3716)
			(drill 0.9652)
			(layers "*.Cu" "*.Mask")
			(remove_unused_layers no)
			(net "GND")
			(clearance 0.1524)
			(thermal_gap 0.1524)
		)
		(pad "5" thru_hole circle
			(at 6.569964 0)
			(size 2.7178 2.7178)
			(drill 2.3114)
			(layers "*.Cu" "*.Mask")
			(remove_unused_layers no)
			(net "AGND_USB")
			(clearance 0.1524)
			(thermal_gap 0.1524)
		)
		(pad "6" thru_hole circle
			(at -6.569964 0)
			(size 2.7178 2.7178)
			(drill 2.3114)
			(layers "*.Cu" "*.Mask")
			(remove_unused_layers no)
			(net "AGND_USB")
			(clearance 0.1524)
			(thermal_gap 0.1524)
		)
	)
	(footprint ""
		(layer "F.Cu")
		(at 62.3062 -161.8996)
		(property "Reference" "PR67"
			(at 0 0 0)
			(layer "F.SilkS")
			(hide yes)
			(effects
				(font
					(size 1.27 1.27)
				)
			)
		)
		(property "Value" "4K75R2F-1-GP"
			(at 0.064008 -3.993896 0)
			(unlocked yes)
			(layer "F.Fab")
			(hide yes)
			(effects
				(font
					(size 1.016 1.016)
					(thickness 0.1524)
				)
			)
		)
		(property "Device Type" "R402H16"
			(at 0.064008 -5.517896 0)
			(unlocked yes)
			(layer "F.Fab")
			(hide yes)
			(effects
				(font
					(size 1.016 1.016)
					(thickness 0.1524)
				)
			)
		)
		(duplicate_pad_numbers_are_jumpers no)
		(fp_line
			(start -0.508 -0.9398)
			(end -0.508 0.9398)
			(stroke
				(width 0.1524)
				(type default)
			)
			(layer "F.SilkS")
		)
		(fp_line
			(start 0.508 -0.9398)
			(end -0.508 -0.9398)
			(stroke
				(width 0.1524)
				(type default)
			)
			(layer "F.SilkS")
		)
		(fp_rect
			(start -0.508 0.9398)
			(end 0.508 -0.9398)
			(stroke
				(width 0)
				(type default)
			)
			(fill no)
			(layer "F.CrtYd")
		)
		(fp_rect
			(start -0.508 0.9398)
			(end 0.508 -0.9398)
			(stroke
				(width 0)
				(type default)
			)
			(fill no)
			(layer "F.Fab")
		)
		(pad "1" smd custom
			(at 0 -0.4445)
			(size 0.1397 0.1397)
			(layers "F.Cu" "F.Mask" "F.Paste")
			(net "VR_P1V538_STBY_FB")
			(options
				(clearance outline)
				(anchor circle)
			)
			(primitives
				(gr_poly
					(pts
						(arc
							(start -0.1778 -0.2794)
							(mid -0.249642 -0.249642)
							(end -0.2794 -0.1778)
						)
						(arc
							(start -0.2794 0.1778)
							(mid -0.249642 0.249642)
							(end -0.1778 0.2794)
						)
						(arc
							(start 0.1778 0.2794)
							(mid 0.249642 0.249642)
							(end 0.2794 0.1778)
						)
						(arc
							(start 0.2794 -0.1778)
							(mid 0.249642 -0.249642)
							(end 0.1778 -0.2794)
						)
					)
					(width 0)
					(fill yes)
				)
			)
		)
		(pad "2" smd custom
			(at 0 0.4445)
			(size 0.1397 0.1397)
			(layers "F.Cu" "F.Mask" "F.Paste")
			(net "GND")
			(options
				(clearance outline)
				(anchor circle)
			)
			(primitives
				(gr_poly
					(pts
						(arc
							(start -0.1778 -0.2794)
							(mid -0.249642 -0.249642)
							(end -0.2794 -0.1778)
						)
						(arc
							(start -0.2794 0.1778)
							(mid -0.249642 0.249642)
							(end -0.1778 0.2794)
						)
						(arc
							(start 0.1778 0.2794)
							(mid 0.249642 0.249642)
							(end 0.2794 0.1778)
						)
						(arc
							(start 0.2794 -0.1778)
							(mid 0.249642 -0.249642)
							(end 0.1778 -0.2794)
						)
					)
					(width 0)
					(fill yes)
				)
			)
		)
	)
	(footprint ""
		(layer "F.Cu")
		(at 31.369 -48.006 -90)
		(property "Reference" "C240"
			(at 0 0 270)
			(layer "F.SilkS")
			(hide yes)
			(effects
				(font
					(size 1.27 1.27)
				)
			)
		)
		(property "Value" "SCD1U16V2JX-1-GP"
			(at 1.1811 -2.7051 270)
			(unlocked yes)
			(layer "F.Fab")
			(hide yes)
			(effects
				(font
					(size 1.016 1.016)
					(thickness 0.1524)
				)
			)
		)
		(property "Device Type" "C402H22"
			(at 1.1811 -4.2291 270)
			(unlocked yes)
			(layer "F.Fab")
			(hide yes)
			(effects
				(font
					(size 1.016 1.016)
					(thickness 0.1524)
				)
			)
		)
		(duplicate_pad_numbers_are_jumpers no)
		(fp_rect
			(start -0.4318 0.9525)
			(end 0.4318 -0.9525)
			(stroke
				(width 0)
				(type default)
			)
			(fill no)
			(layer "F.CrtYd")
		)
		(fp_rect
			(start -0.4318 0.9525)
			(end 0.4318 -0.9525)
			(stroke
				(width 0)
				(type default)
			)
			(fill no)
			(layer "F.Fab")
		)
		(pad "1" smd custom
			(at 0 -0.4445 270)
			(size 0.1524 0.1524)
			(layers "F.Cu" "F.Mask" "F.Paste")
			(net "P5V_USB")
			(options
				(clearance outline)
				(anchor circle)
			)
			(primitives
				(gr_poly
					(pts
						(arc
							(start 0.3048 -0.2032)
							(mid 0.275042 -0.275042)
							(end 0.2032 -0.3048)
						)
						(arc
							(start -0.2032 -0.3048)
							(mid -0.275042 -0.275042)
							(end -0.3048 -0.2032)
						)
						(arc
							(start -0.3048 0.2032)
							(mid -0.275042 0.275042)
							(end -0.2032 0.3048)
						)
						(arc
							(start 0.2032 0.3048)
							(mid 0.275042 0.275042)
							(end 0.3048 0.2032)
						)
					)
					(width 0)
					(fill yes)
				)
			)
		)
		(pad "2" smd custom
			(at 0 0.4445 270)
			(size 0.1524 0.1524)
			(layers "F.Cu" "F.Mask" "F.Paste")
			(net "GND")
			(options
				(clearance outline)
				(anchor circle)
			)
			(primitives
				(gr_poly
					(pts
						(arc
							(start 0.3048 -0.2032)
							(mid 0.275042 -0.275042)
							(end 0.2032 -0.3048)
						)
						(arc
							(start -0.2032 -0.3048)
							(mid -0.275042 -0.275042)
							(end -0.3048 -0.2032)
						)
						(arc
							(start -0.3048 0.2032)
							(mid -0.275042 0.275042)
							(end -0.2032 0.3048)
						)
						(arc
							(start 0.2032 0.3048)
							(mid 0.275042 0.275042)
							(end 0.3048 0.2032)
						)
					)
					(width 0)
					(fill yes)
				)
			)
		)
	)
	(footprint ""
		(layer "F.Cu")
		(at 16.578326 -127.56388 90)
		(property "Reference" "R407"
			(at 0 0 90)
			(layer "F.SilkS")
			(hide yes)
			(effects
				(font
					(size 1.27 1.27)
				)
			)
		)
		(property "Value" "10KR2F-2-GP"
			(at 0.064008 -3.993896 90)
			(unlocked yes)
			(layer "F.Fab")
			(hide yes)
			(effects
				(font
					(size 1.016 1.016)
					(thickness 0.1524)
				)
			)
		)
		(property "Device Type" "R402H16"
			(at 0.064008 -5.517896 90)
			(unlocked yes)
			(layer "F.Fab")
			(hide yes)
			(effects
				(font
					(size 1.016 1.016)
					(thickness 0.1524)
				)
			)
		)
		(duplicate_pad_numbers_are_jumpers no)
		(fp_line
			(start 0.508 -0.9398)
			(end -0.508 -0.9398)
			(stroke
				(width 0.1524)
				(type default)
			)
			(layer "F.SilkS")
		)
		(fp_line
			(start -0.508 -0.9398)
			(end -0.508 0.9398)
			(stroke
				(width 0.1524)
				(type default)
			)
			(layer "F.SilkS")
		)
		(fp_rect
			(start -0.508 0.9398)
			(end 0.508 -0.9398)
			(stroke
				(width 0)
				(type default)
			)
			(fill no)
			(layer "F.CrtYd")
		)
		(fp_rect
			(start -0.508 0.9398)
			(end 0.508 -0.9398)
			(stroke
				(width 0)
				(type default)
			)
			(fill no)
			(layer "F.Fab")
		)
		(pad "1" smd custom
			(at 0 -0.4445 90)
			(size 0.1397 0.1397)
			(layers "F.Cu" "F.Mask" "F.Paste")
			(net "P3V3_STBY")
			(options
				(clearance outline)
				(anchor circle)
			)
			(primitives
				(gr_poly
					(pts
						(arc
							(start -0.1778 -0.2794)
							(mid -0.249642 -0.249642)
							(end -0.2794 -0.1778)
						)
						(arc
							(start -0.2794 0.1778)
							(mid -0.249642 0.249642)
							(end -0.1778 0.2794)
						)
						(arc
							(start 0.1778 0.2794)
							(mid 0.249642 0.249642)
							(end 0.2794 0.1778)
						)
						(arc
							(start 0.2794 -0.1778)
							(mid 0.249642 -0.249642)
							(end 0.1778 -0.2794)
						)
					)
					(width 0)
					(fill yes)
				)
			)
		)
		(pad "2" smd custom
			(at 0 0.4445 90)
			(size 0.1397 0.1397)
			(layers "F.Cu" "F.Mask" "F.Paste")
			(net "PE1_PERST#")
			(options
				(clearance outline)
				(anchor circle)
			)
			(primitives
				(gr_poly
					(pts
						(arc
							(start -0.1778 -0.2794)
							(mid -0.249642 -0.249642)
							(end -0.2794 -0.1778)
						)
						(arc
							(start -0.2794 0.1778)
							(mid -0.249642 0.249642)
							(end -0.1778 0.2794)
						)
						(arc
							(start 0.1778 0.2794)
							(mid 0.249642 0.249642)
							(end 0.2794 0.1778)
						)
						(arc
							(start 0.2794 -0.1778)
							(mid 0.249642 -0.249642)
							(end 0.1778 -0.2794)
						)
					)
					(width 0)
					(fill yes)
				)
			)
		)
	)
	(footprint ""
		(layer "F.Cu")
		(at 229.108 -92.202 90)
		(property "Reference" "R585"
			(at 0 0 90)
			(layer "F.SilkS")
			(hide yes)
			(effects
				(font
					(size 1.27 1.27)
				)
			)
		)
		(property "Value" "4K7R2F-GP"
			(at 0.064008 -3.993896 90)
			(unlocked yes)
			(layer "F.Fab")
			(hide yes)
			(effects
				(font
					(size 1.016 1.016)
					(thickness 0.1524)
				)
			)
		)
		(property "Device Type" "R402H16"
			(at 0.064008 -5.517896 90)
			(unlocked yes)
			(layer "F.Fab")
			(hide yes)
			(effects
				(font
					(size 1.016 1.016)
					(thickness 0.1524)
				)
			)
		)
		(duplicate_pad_numbers_are_jumpers no)
		(fp_line
			(start 0.508 -0.9398)
			(end -0.508 -0.9398)
			(stroke
				(width 0.1524)
				(type default)
			)
			(layer "F.SilkS")
		)
		(fp_line
			(start -0.508 -0.9398)
			(end -0.508 0.9398)
			(stroke
				(width 0.1524)
				(type default)
			)
			(layer "F.SilkS")
		)
		(fp_rect
			(start -0.508 0.9398)
			(end 0.508 -0.9398)
			(stroke
				(width 0)
				(type default)
			)
			(fill no)
			(layer "F.CrtYd")
		)
		(fp_rect
			(start -0.508 0.9398)
			(end 0.508 -0.9398)
			(stroke
				(width 0)
				(type default)
			)
			(fill no)
			(layer "F.Fab")
		)
		(pad "1" smd custom
			(at 0 -0.4445 90)
			(size 0.1397 0.1397)
			(layers "F.Cu" "F.Mask" "F.Paste")
			(net "TEMP_3_A0")
			(options
				(clearance outline)
				(anchor circle)
			)
			(primitives
				(gr_poly
					(pts
						(arc
							(start -0.1778 -0.2794)
							(mid -0.249642 -0.249642)
							(end -0.2794 -0.1778)
						)
						(arc
							(start -0.2794 0.1778)
							(mid -0.249642 0.249642)
							(end -0.1778 0.2794)
						)
						(arc
							(start 0.1778 0.2794)
							(mid 0.249642 0.249642)
							(end 0.2794 0.1778)
						)
						(arc
							(start 0.2794 -0.1778)
							(mid 0.249642 -0.249642)
							(end 0.1778 -0.2794)
						)
					)
					(width 0)
					(fill yes)
				)
			)
		)
		(pad "2" smd custom
			(at 0 0.4445 90)
			(size 0.1397 0.1397)
			(layers "F.Cu" "F.Mask" "F.Paste")
			(net "GND")
			(options
				(clearance outline)
				(anchor circle)
			)
			(primitives
				(gr_poly
					(pts
						(arc
							(start -0.1778 -0.2794)
							(mid -0.249642 -0.249642)
							(end -0.2794 -0.1778)
						)
						(arc
							(start -0.2794 0.1778)
							(mid -0.249642 0.249642)
							(end -0.1778 0.2794)
						)
						(arc
							(start 0.1778 0.2794)
							(mid 0.249642 0.249642)
							(end 0.2794 0.1778)
						)
						(arc
							(start 0.2794 -0.1778)
							(mid 0.249642 -0.249642)
							(end 0.1778 -0.2794)
						)
					)
					(width 0)
					(fill yes)
				)
			)
		)
	)
	(footprint ""
		(layer "F.Cu")
		(at 319.659 -86.487 180)
		(property "Reference" "R527"
			(at 0 0 180)
			(layer "F.SilkS")
			(hide yes)
			(effects
				(font
					(size 1.27 1.27)
				)
			)
		)
		(property "Value" "10KR2F-2-GP"
			(at 0.064008 -3.993896 180)
			(unlocked yes)
			(layer "F.Fab")
			(hide yes)
			(effects
				(font
					(size 1.016 1.016)
					(thickness 0.1524)
				)
			)
		)
		(property "Device Type" "R402H16"
			(at 0.064008 -5.517896 180)
			(unlocked yes)
			(layer "F.Fab")
			(hide yes)
			(effects
				(font
					(size 1.016 1.016)
					(thickness 0.1524)
				)
			)
		)
		(duplicate_pad_numbers_are_jumpers no)
		(fp_line
			(start 0.508 -0.9398)
			(end -0.508 -0.9398)
			(stroke
				(width 0.1524)
				(type default)
			)
			(layer "F.SilkS")
		)
		(fp_line
			(start -0.508 -0.9398)
			(end -0.508 0.9398)
			(stroke
				(width 0.1524)
				(type default)
			)
			(layer "F.SilkS")
		)
		(fp_rect
			(start -0.508 0.9398)
			(end 0.508 -0.9398)
			(stroke
				(width 0)
				(type default)
			)
			(fill no)
			(layer "F.CrtYd")
		)
		(fp_rect
			(start -0.508 0.9398)
			(end 0.508 -0.9398)
			(stroke
				(width 0)
				(type default)
			)
			(fill no)
			(layer "F.Fab")
		)
		(pad "1" smd custom
			(at 0 -0.4445 180)
			(size 0.1397 0.1397)
			(layers "F.Cu" "F.Mask" "F.Paste")
			(net "GND")
			(options
				(clearance outline)
				(anchor circle)
			)
			(primitives
				(gr_poly
					(pts
						(arc
							(start -0.1778 -0.2794)
							(mid -0.249642 -0.249642)
							(end -0.2794 -0.1778)
						)
						(arc
							(start -0.2794 0.1778)
							(mid -0.249642 0.249642)
							(end -0.1778 0.2794)
						)
						(arc
							(start 0.1778 0.2794)
							(mid 0.249642 0.249642)
							(end 0.2794 0.1778)
						)
						(arc
							(start 0.2794 -0.1778)
							(mid 0.249642 -0.249642)
							(end 0.1778 -0.2794)
						)
					)
					(width 0)
					(fill yes)
				)
			)
		)
		(pad "2" smd custom
			(at 0 0.4445 180)
			(size 0.1397 0.1397)
			(layers "F.Cu" "F.Mask" "F.Paste")
			(net "IOEXP_PMC1_AD1")
			(options
				(clearance outline)
				(anchor circle)
			)
			(primitives
				(gr_poly
					(pts
						(arc
							(start -0.1778 -0.2794)
							(mid -0.249642 -0.249642)
							(end -0.2794 -0.1778)
						)
						(arc
							(start -0.2794 0.1778)
							(mid -0.249642 0.249642)
							(end -0.1778 0.2794)
						)
						(arc
							(start 0.1778 0.2794)
							(mid 0.249642 0.249642)
							(end 0.2794 0.1778)
						)
						(arc
							(start 0.2794 -0.1778)
							(mid 0.249642 -0.249642)
							(end 0.1778 -0.2794)
						)
					)
					(width 0)
					(fill yes)
				)
			)
		)
	)
)
